# T6G (Grand Teton) — schematic netlist excerpt (pin names and nets, part order shuffled) for the footprints in the layout excerpt that follows; sources: Cadence DE-HDL packaged netlist, KiCad conversion of 04192023_DAF0TMB3IC0_F0TG_MB_C_brd_V02_OCP.brd

R4543  Q_RES  1K 1% CHIP  pkg 0402LF  page 124 : A = P3V3_AUX ; B = HGX_DETECT_N
C790  Q_CAP  0.1UF 10V 10% X7S  pkg C0201  page 301 : A = P0V9_CPU0_RT2_2A ; B = GND
R4122  Q_RES  100K 1% EMPTY  pkg 0402LF  page 125 : A = PRSNT_CABLE_GPU_B3_N ; B = GND

(kicad_pcb
	(version 20260206)
	(generator "pcbnew")
	(generator_version "10.0")
	(general
		(thickness 1.6)
		(legacy_teardrops no)
	)
	(paper "A4")
	(title_block
		(title "04192023_DAF0TMB3IC0_F0TG_MB_C_brd_V02_OCP.brd")
		(comment 1 "Grand Teton / footprints 5998-6000 of 8354")
	)
	(layers
		(0 "F.Cu" signal "TOP")
		(4 "In1.Cu" signal "GND")
		(6 "In2.Cu" signal "IN1")
		(8 "In3.Cu" signal "GND1")
		(10 "In4.Cu" signal "IN2")
		(12 "In5.Cu" signal "GND2")
		(14 "In6.Cu" signal "IN3")
		(16 "In7.Cu" signal "GND3")
		(18 "In8.Cu" signal "VCC")
		(20 "In9.Cu" signal "VCC1")
		(22 "In10.Cu" signal "GND4")
		(24 "In11.Cu" signal "IN4")
		(26 "In12.Cu" signal "GND5")
		(28 "In13.Cu" signal "IN5")
		(30 "In14.Cu" signal "GND6")
		(32 "In15.Cu" signal "IN6")
		(34 "In16.Cu" signal "GND7")
		(2 "B.Cu" signal "BOTTOM")
		(9 "F.Adhes" user "F.Adhesive")
		(11 "B.Adhes" user "B.Adhesive")
		(13 "F.Paste" user "Package Geometry/Pastemask Top")
		(15 "B.Paste" user "Package Geometry/Pastemask Bottom")
		(5 "F.SilkS" user "Ref Des/Silkscreen Top")
		(7 "B.SilkS" user "Ref Des/Silkscreen Bottom")
		(1 "F.Mask" user "Board Geometry/Soldermask Top")
		(3 "B.Mask" user "Board Geometry/Soldermask Bottom")
		(17 "Dwgs.User" user "User.Drawings")
		(19 "Cmts.User" user "User.Comments")
		(21 "Eco1.User" user "User.Eco1")
		(23 "Eco2.User" user "User.Eco2")
		(25 "Edge.Cuts" user "Board Geometry/Outline")
		(27 "Margin" user)
		(31 "F.CrtYd" user "Package Geometry/Place Bound Top")
		(29 "B.CrtYd" user "Package Geometry/Place Bound Bottom")
		(35 "F.Fab" user "Ref Des/Assembly Top")
		(33 "B.Fab" user "Ref Des/Assembly Bottom")
	)
	(footprint ""
		(layer "B.Cu")
		(at 164.403532 -434.15458 90)
		(property "Reference" "R4122"
			(at 0 0 90)
			(layer "B.SilkS")
			(hide yes)
			(effects
				(font
					(size 1.27 1.27)
				)
				(justify mirror)
			)
		)
		(property "Value" ""
			(at 0 0 90)
			(layer "B.Fab")
			(effects
				(font
					(size 1.27 1.27)
				)
				(justify mirror)
			)
		)
		(duplicate_pad_numbers_are_jumpers no)
		(fp_line
			(start 0.7874 -0.4064)
			(end -0.7874 -0.4064)
			(stroke
				(width 0.1524)
				(type default)
			)
			(layer "B.SilkS")
		)
		(fp_line
			(start -0.7874 -0.4064)
			(end -0.7874 0.4064)
			(stroke
				(width 0.1524)
				(type default)
			)
			(layer "B.SilkS")
		)
		(fp_line
			(start 0.7874 0.4064)
			(end 0.7874 -0.4064)
			(stroke
				(width 0.1524)
				(type default)
			)
			(layer "B.SilkS")
		)
		(fp_line
			(start -0.7874 0.4064)
			(end 0.7874 0.4064)
			(stroke
				(width 0.1524)
				(type default)
			)
			(layer "B.SilkS")
		)
		(fp_line
			(start 0.67945 -0.305054)
			(end 0.12065 -0.305054)
			(stroke
				(width 0.1)
				(type default)
			)
			(layer "B.Fab")
		)
		(fp_line
			(start 0.12065 -0.305054)
			(end 0.12065 -0.2794)
			(stroke
				(width 0.1)
				(type default)
			)
			(layer "B.Fab")
		)
		(fp_line
			(start -0.12065 -0.3048)
			(end -0.67945 -0.3048)
			(stroke
				(width 0.1)
				(type default)
			)
			(layer "B.Fab")
		)
		(fp_line
			(start -0.67945 -0.3048)
			(end -0.67945 0.3048)
			(stroke
				(width 0.1)
				(type default)
			)
			(layer "B.Fab")
		)
		(fp_line
			(start 0.12065 -0.2794)
			(end -0.12065 -0.2794)
			(stroke
				(width 0.1)
				(type default)
			)
			(layer "B.Fab")
		)
		(fp_line
			(start -0.12065 -0.2794)
			(end -0.12065 -0.3048)
			(stroke
				(width 0.1)
				(type default)
			)
			(layer "B.Fab")
		)
		(fp_line
			(start 0.12065 0.2794)
			(end 0.12065 0.3048)
			(stroke
				(width 0.1)
				(type default)
			)
			(layer "B.Fab")
		)
		(fp_line
			(start -0.120396 0.2794)
			(end 0.12065 0.2794)
			(stroke
				(width 0.1)
				(type default)
			)
			(layer "B.Fab")
		)
		(fp_line
			(start 0.67945 0.3048)
			(end 0.67945 -0.305054)
			(stroke
				(width 0.1)
				(type default)
			)
			(layer "B.Fab")
		)
		(fp_line
			(start 0.12065 0.3048)
			(end 0.67945 0.3048)
			(stroke
				(width 0.1)
				(type default)
			)
			(layer "B.Fab")
		)
		(fp_line
			(start -0.120396 0.3048)
			(end -0.120396 0.2794)
			(stroke
				(width 0.1)
				(type default)
			)
			(layer "B.Fab")
		)
		(fp_line
			(start -0.67945 0.3048)
			(end -0.120396 0.3048)
			(stroke
				(width 0.1)
				(type default)
			)
			(layer "B.Fab")
		)
		(pad "1" smd circle
			(at 0.40005 0 270)
			(size 0 0)
			(layers "B.Cu" "B.Mask" "B.Paste")
			(net "PRSNT_CABLE_GPU_B3_N")
		)
		(pad "2" smd circle
			(at -0.40005 0 270)
			(size 0 0)
			(layers "B.Cu" "B.Mask" "B.Paste")
			(net "GND")
		)
	)
	(footprint ""
		(layer "B.Cu")
		(at 421.146224 -396.393162 -90)
		(property "Reference" "C790"
			(at 0 0 90)
			(layer "B.SilkS")
			(hide yes)
			(effects
				(font
					(size 1.27 1.27)
				)
				(justify mirror)
			)
		)
		(property "Value" ""
			(at 0 0 90)
			(layer "B.Fab")
			(effects
				(font
					(size 1.27 1.27)
				)
				(justify mirror)
			)
		)
		(duplicate_pad_numbers_are_jumpers no)
		(fp_line
			(start -0.299974 0.150114)
			(end 0.299974 0.150114)
			(stroke
				(width 0.1)
				(type default)
			)
			(layer "B.Fab")
		)
		(fp_line
			(start 0.299974 0.150114)
			(end 0.299974 -0.150114)
			(stroke
				(width 0.1)
				(type default)
			)
			(layer "B.Fab")
		)
		(fp_line
			(start -0.299974 -0.150114)
			(end -0.299974 0.150114)
			(stroke
				(width 0.1)
				(type default)
			)
			(layer "B.Fab")
		)
		(fp_line
			(start 0.299974 -0.150114)
			(end -0.299974 -0.150114)
			(stroke
				(width 0.1)
				(type default)
			)
			(layer "B.Fab")
		)
		(pad "1" smd rect
			(at 0.2667 0 90)
			(size 0.3048 0.381)
			(layers "B.Cu" "B.Mask" "B.Paste")
			(net "P0V9_CPU0_RT2_2A")
		)
		(pad "2" smd rect
			(at -0.2667 0 90)
			(size 0.3048 0.381)
			(layers "B.Cu" "B.Mask" "B.Paste")
			(net "GND")
		)
	)
	(footprint ""
		(layer "B.Cu")
		(at 104.648 -415.925 90)
		(property "Reference" "R4543"
			(at 0 0 90)
			(layer "B.SilkS")
			(hide yes)
			(effects
				(font
					(size 1.27 1.27)
				)
				(justify mirror)
			)
		)
		(property "Value" ""
			(at 0 0 90)
			(layer "B.Fab")
			(effects
				(font
					(size 1.27 1.27)
				)
				(justify mirror)
			)
		)
		(duplicate_pad_numbers_are_jumpers no)
		(fp_line
			(start 0.7874 -0.4064)
			(end -0.7874 -0.4064)
			(stroke
				(width 0.1524)
				(type default)
			)
			(layer "B.SilkS")
		)
		(fp_line
			(start -0.7874 -0.4064)
			(end -0.7874 0.4064)
			(stroke
				(width 0.1524)
				(type default)
			)
			(layer "B.SilkS")
		)
		(fp_line
			(start 0.7874 0.4064)
			(end 0.7874 -0.4064)
			(stroke
				(width 0.1524)
				(type default)
			)
			(layer "B.SilkS")
		)
		(fp_line
			(start -0.7874 0.4064)
			(end 0.7874 0.4064)
			(stroke
				(width 0.1524)
				(type default)
			)
			(layer "B.SilkS")
		)
		(fp_line
			(start 0.67945 -0.305054)
			(end 0.12065 -0.305054)
			(stroke
				(width 0.1)
				(type default)
			)
			(layer "B.Fab")
		)
		(fp_line
			(start 0.12065 -0.305054)
			(end 0.12065 -0.2794)
			(stroke
				(width 0.1)
				(type default)
			)
			(layer "B.Fab")
		)
		(fp_line
			(start -0.12065 -0.3048)
			(end -0.67945 -0.3048)
			(stroke
				(width 0.1)
				(type default)
			)
			(layer "B.Fab")
		)
		(fp_line
			(start -0.67945 -0.3048)
			(end -0.67945 0.3048)
			(stroke
				(width 0.1)
				(type default)
			)
			(layer "B.Fab")
		)
		(fp_line
			(start 0.12065 -0.2794)
			(end -0.12065 -0.2794)
			(stroke
				(width 0.1)
				(type default)
			)
			(layer "B.Fab")
		)
		(fp_line
			(start -0.12065 -0.2794)
			(end -0.12065 -0.3048)
			(stroke
				(width 0.1)
				(type default)
			)
			(layer "B.Fab")
		)
		(fp_line
			(start 0.12065 0.2794)
			(end 0.12065 0.3048)
			(stroke
				(width 0.1)
				(type default)
			)
			(layer "B.Fab")
		)
		(fp_line
			(start -0.120396 0.2794)
			(end 0.12065 0.2794)
			(stroke
				(width 0.1)
				(type default)
			)
			(layer "B.Fab")
		)
		(fp_line
			(start 0.67945 0.3048)
			(end 0.67945 -0.305054)
			(stroke
				(width 0.1)
				(type default)
			)
			(layer "B.Fab")
		)
		(fp_line
			(start 0.12065 0.3048)
			(end 0.67945 0.3048)
			(stroke
				(width 0.1)
				(type default)
			)
			(layer "B.Fab")
		)
		(fp_line
			(start -0.120396 0.3048)
			(end -0.120396 0.2794)
			(stroke
				(width 0.1)
				(type default)
			)
			(layer "B.Fab")
		)
		(fp_line
			(start -0.67945 0.3048)
			(end -0.120396 0.3048)
			(stroke
				(width 0.1)
				(type default)
			)
			(layer "B.Fab")
		)
		(pad "1" smd circle
			(at 0.40005 0 270)
			(size 0 0)
			(layers "B.Cu" "B.Mask" "B.Paste")
			(net "P3V3_AUX")
		)
		(pad "2" smd circle
			(at -0.40005 0 270)
			(size 0 0)
			(layers "B.Cu" "B.Mask" "B.Paste")
			(net "HGX_DETECT_N")
		)
	)
)
